# S9S_MB_2U (Grand Teton) — schematic netlist excerpt (pin names and nets, part order shuffled) for the footprints in the layout excerpt that follows; sources: Cadence DE-HDL packaged netlist, KiCad conversion of 03242023_DA0F0TMBIJ0_F0T_Motherboard_J_brd_V01_OCP.brd

R721  Q_RES  10K 1% CHIP  pkg 0402LF  page 243 : A = P3V3_AUX ; B = MB_FRU_ADDR0
R4408  Q_RES  33.2 1% CHIP  pkg 0402LF  page 122 : A = H_CPU1_MEMHOT_OUT_VT_N ; B = H_CPU1_MEMHOT_OUT_LVC1_N

(kicad_pcb
	(version 20260206)
	(generator "pcbnew")
	(generator_version "10.0")
	(general
		(thickness 1.6)
		(legacy_teardrops no)
	)
	(paper "A4")
	(title_block
		(title "03242023_DA0F0TMBIJ0_F0T_Motherboard_J_brd_V01_OCP.brd")
		(comment 1 "Grand Teton / footprints 1685-1686 of 6105")
	)
	(layers
		(0 "F.Cu" signal "TOP")
		(4 "In1.Cu" signal "GND")
		(6 "In2.Cu" signal "IN1")
		(8 "In3.Cu" signal "GND1")
		(10 "In4.Cu" signal "IN2")
		(12 "In5.Cu" signal "GND2")
		(14 "In6.Cu" signal "IN3")
		(16 "In7.Cu" signal "GND3")
		(18 "In8.Cu" signal "VCC")
		(20 "In9.Cu" signal "VCC1")
		(22 "In10.Cu" signal "GND4")
		(24 "In11.Cu" signal "IN4")
		(26 "In12.Cu" signal "GND5")
		(28 "In13.Cu" signal "IN5")
		(30 "In14.Cu" signal "GND6")
		(32 "In15.Cu" signal "IN6")
		(34 "In16.Cu" signal "GND7")
		(2 "B.Cu" signal "BOTTOM")
		(9 "F.Adhes" user "F.Adhesive")
		(11 "B.Adhes" user "B.Adhesive")
		(13 "F.Paste" user "Package Geometry/Pastemask Top")
		(15 "B.Paste" user "Package Geometry/Pastemask Bottom")
		(5 "F.SilkS" user "Ref Des/Silkscreen Top")
		(7 "B.SilkS" user "Ref Des/Silkscreen Bottom")
		(1 "F.Mask" user "Board Geometry/Soldermask Top")
		(3 "B.Mask" user "Board Geometry/Soldermask Bottom")
		(17 "Dwgs.User" user "User.Drawings")
		(19 "Cmts.User" user "User.Comments")
		(21 "Eco1.User" user "User.Eco1")
		(23 "Eco2.User" user "User.Eco2")
		(25 "Edge.Cuts" user "Board Geometry/Outline")
		(27 "Margin" user)
		(31 "F.CrtYd" user "Package Geometry/Place Bound Top")
		(29 "B.CrtYd" user "Package Geometry/Place Bound Bottom")
		(35 "F.Fab" user "Ref Des/Assembly Top")
		(33 "B.Fab" user "Ref Des/Assembly Bottom")
	)
	(footprint ""
		(layer "F.Cu")
		(at 277.64994 -96.329754)
		(property "Reference" "R721"
			(at 0 0 0)
			(layer "F.SilkS")
			(hide yes)
			(effects
				(font
					(size 1.27 1.27)
				)
			)
		)
		(property "Value" ""
			(at 0 0 0)
			(layer "F.Fab")
			(effects
				(font
					(size 1.27 1.27)
				)
			)
		)
		(duplicate_pad_numbers_are_jumpers no)
		(fp_line
			(start -0.7874 -0.4064)
			(end 0.7874 -0.4064)
			(stroke
				(width 0.1524)
				(type default)
			)
			(layer "F.SilkS")
		)
		(fp_line
			(start -0.7874 0.4064)
			(end -0.7874 -0.4064)
			(stroke
				(width 0.1524)
				(type default)
			)
			(layer "F.SilkS")
		)
		(fp_line
			(start 0.7874 -0.4064)
			(end 0.7874 0.4064)
			(stroke
				(width 0.1524)
				(type default)
			)
			(layer "F.SilkS")
		)
		(fp_line
			(start 0.7874 0.4064)
			(end -0.7874 0.4064)
			(stroke
				(width 0.1524)
				(type default)
			)
			(layer "F.SilkS")
		)
		(fp_line
			(start -0.67945 -0.305054)
			(end -0.12065 -0.305054)
			(stroke
				(width 0.1)
				(type default)
			)
			(layer "F.Fab")
		)
		(fp_line
			(start -0.67945 0.3048)
			(end -0.67945 -0.305054)
			(stroke
				(width 0.1)
				(type default)
			)
			(layer "F.Fab")
		)
		(fp_line
			(start -0.12065 -0.305054)
			(end -0.12065 -0.2794)
			(stroke
				(width 0.1)
				(type default)
			)
			(layer "F.Fab")
		)
		(fp_line
			(start -0.12065 -0.2794)
			(end 0.12065 -0.2794)
			(stroke
				(width 0.1)
				(type default)
			)
			(layer "F.Fab")
		)
		(fp_line
			(start -0.12065 0.2794)
			(end -0.12065 0.3048)
			(stroke
				(width 0.1)
				(type default)
			)
			(layer "F.Fab")
		)
		(fp_line
			(start -0.12065 0.3048)
			(end -0.67945 0.3048)
			(stroke
				(width 0.1)
				(type default)
			)
			(layer "F.Fab")
		)
		(fp_line
			(start 0.120396 0.2794)
			(end -0.12065 0.2794)
			(stroke
				(width 0.1)
				(type default)
			)
			(layer "F.Fab")
		)
		(fp_line
			(start 0.120396 0.3048)
			(end 0.120396 0.2794)
			(stroke
				(width 0.1)
				(type default)
			)
			(layer "F.Fab")
		)
		(fp_line
			(start 0.12065 -0.3048)
			(end 0.67945 -0.3048)
			(stroke
				(width 0.1)
				(type default)
			)
			(layer "F.Fab")
		)
		(fp_line
			(start 0.12065 -0.2794)
			(end 0.12065 -0.3048)
			(stroke
				(width 0.1)
				(type default)
			)
			(layer "F.Fab")
		)
		(fp_line
			(start 0.67945 -0.3048)
			(end 0.67945 0.3048)
			(stroke
				(width 0.1)
				(type default)
			)
			(layer "F.Fab")
		)
		(fp_line
			(start 0.67945 0.3048)
			(end 0.120396 0.3048)
			(stroke
				(width 0.1)
				(type default)
			)
			(layer "F.Fab")
		)
		(pad "1" smd circle
			(at -0.40005 0)
			(size 0 0)
			(layers "F.Cu" "F.Mask" "F.Paste")
			(net "P3V3_AUX")
		)
		(pad "2" smd circle
			(at 0.40005 0)
			(size 0 0)
			(layers "F.Cu" "F.Mask" "F.Paste")
			(net "MB_FRU_ADDR0")
		)
	)
	(footprint ""
		(layer "F.Cu")
		(at 135.05688 -92.674948 -90)
		(property "Reference" "R4408"
			(at 0 0 270)
			(layer "F.SilkS")
			(hide yes)
			(effects
				(font
					(size 1.27 1.27)
				)
			)
		)
		(property "Value" ""
			(at 0 0 270)
			(layer "F.Fab")
			(effects
				(font
					(size 1.27 1.27)
				)
			)
		)
		(duplicate_pad_numbers_are_jumpers no)
		(fp_line
			(start -0.7874 0.4064)
			(end -0.7874 -0.4064)
			(stroke
				(width 0.1524)
				(type default)
			)
			(layer "F.SilkS")
		)
		(fp_line
			(start 0.7874 0.4064)
			(end -0.7874 0.4064)
			(stroke
				(width 0.1524)
				(type default)
			)
			(layer "F.SilkS")
		)
		(fp_line
			(start -0.7874 -0.4064)
			(end 0.7874 -0.4064)
			(stroke
				(width 0.1524)
				(type default)
			)
			(layer "F.SilkS")
		)
		(fp_line
			(start 0.7874 -0.4064)
			(end 0.7874 0.4064)
			(stroke
				(width 0.1524)
				(type default)
			)
			(layer "F.SilkS")
		)
		(fp_line
			(start -0.67945 0.3048)
			(end -0.67945 -0.305054)
			(stroke
				(width 0.1)
				(type default)
			)
			(layer "F.Fab")
		)
		(fp_line
			(start -0.12065 0.3048)
			(end -0.67945 0.3048)
			(stroke
				(width 0.1)
				(type default)
			)
			(layer "F.Fab")
		)
		(fp_line
			(start 0.120396 0.3048)
			(end 0.120396 0.2794)
			(stroke
				(width 0.1)
				(type default)
			)
			(layer "F.Fab")
		)
		(fp_line
			(start 0.67945 0.3048)
			(end 0.120396 0.3048)
			(stroke
				(width 0.1)
				(type default)
			)
			(layer "F.Fab")
		)
		(fp_line
			(start -0.12065 0.2794)
			(end -0.12065 0.3048)
			(stroke
				(width 0.1)
				(type default)
			)
			(layer "F.Fab")
		)
		(fp_line
			(start 0.120396 0.2794)
			(end -0.12065 0.2794)
			(stroke
				(width 0.1)
				(type default)
			)
			(layer "F.Fab")
		)
		(fp_line
			(start -0.12065 -0.2794)
			(end 0.12065 -0.2794)
			(stroke
				(width 0.1)
				(type default)
			)
			(layer "F.Fab")
		)
		(fp_line
			(start 0.12065 -0.2794)
			(end 0.12065 -0.3048)
			(stroke
				(width 0.1)
				(type default)
			)
			(layer "F.Fab")
		)
		(fp_line
			(start 0.12065 -0.3048)
			(end 0.67945 -0.3048)
			(stroke
				(width 0.1)
				(type default)
			)
			(layer "F.Fab")
		)
		(fp_line
			(start 0.67945 -0.3048)
			(end 0.67945 0.3048)
			(stroke
				(width 0.1)
				(type default)
			)
			(layer "F.Fab")
		)
		(fp_line
			(start -0.67945 -0.305054)
			(end -0.12065 -0.305054)
			(stroke
				(width 0.1)
				(type default)
			)
			(layer "F.Fab")
		)
		(fp_line
			(start -0.12065 -0.305054)
			(end -0.12065 -0.2794)
			(stroke
				(width 0.1)
				(type default)
			)
			(layer "F.Fab")
		)
		(pad "1" smd circle
			(at -0.40005 0 270)
			(size 0 0)
			(layers "F.Cu" "F.Mask" "F.Paste")
			(net "H_CPU1_MEMHOT_OUT_VT_N")
		)
		(pad "2" smd circle
			(at 0.40005 0 270)
			(size 0 0)
			(layers "F.Cu" "F.Mask" "F.Paste")
			(net "H_CPU1_MEMHOT_OUT_LVC1_N")
		)
	)
)
